# TIMECARD (Time Appliance Project (Time Card)) — schematic netlist excerpt (pin names and nets, part order shuffled) for the footprints in the layout excerpt that follows; sources: Cadence DE-HDL packaged netlist, KiCad conversion of R4006-B0001-02_R01.brd

TP184  TP_PIONT  pkg TP010CT020B030_PTH  page 25 : \1\ = IO_L22N_16
R193  RESISTOR  4.7KOHM 1%  pkg SMC_0402R_H016  page 10 : \1\ = XP3R3V_FPGA ; \2\ = FPGA_PROGRAM_N

(kicad_pcb
	(version 20260206)
	(generator "pcbnew")
	(generator_version "10.0")
	(general
		(thickness 1.6)
		(legacy_teardrops no)
	)
	(paper "A4")
	(title_block
		(title "timecard-production-celestica-r4006 — R4006-B0001-02_R01.brd")
		(comment 1 "Time Appliance Project (Time Card) / footprints 449-450 of 1113")
	)
	(layers
		(0 "F.Cu" signal "TOP")
		(4 "In1.Cu" signal "L02_GND1")
		(6 "In2.Cu" signal "L03_SIG1")
		(8 "In3.Cu" signal "L04_GND2")
		(10 "In4.Cu" signal "L05_VCC1")
		(12 "In5.Cu" signal "L06_VCC2")
		(14 "In6.Cu" signal "L07_GND3")
		(16 "In7.Cu" signal "L08_SIG2")
		(18 "In8.Cu" signal "L09_GND4")
		(2 "B.Cu" signal "BOTTOM")
		(9 "F.Adhes" user "F.Adhesive")
		(11 "B.Adhes" user "B.Adhesive")
		(13 "F.Paste" user "Package Geometry/Pastemask Top")
		(15 "B.Paste" user "Package Geometry/Pastemask Bottom")
		(5 "F.SilkS" user "Ref Des/Silkscreen Top")
		(7 "B.SilkS" user "Ref Des/Silkscreen Bottom")
		(1 "F.Mask" user "Board Geometry/Soldermask Top")
		(3 "B.Mask" user "Board Geometry/Soldermask Bottom")
		(17 "Dwgs.User" user "User.Drawings")
		(19 "Cmts.User" user "User.Comments")
		(21 "Eco1.User" user "User.Eco1")
		(23 "Eco2.User" user "User.Eco2")
		(25 "Edge.Cuts" user "Board Geometry/Outline")
		(27 "Margin" user)
		(31 "F.CrtYd" user "Package Geometry/Place Bound Top")
		(29 "B.CrtYd" user "Package Geometry/Place Bound Bottom")
		(35 "F.Fab" user "Ref Des/Assembly Top")
		(33 "B.Fab" user "Ref Des/Assembly Bottom")
	)
	(footprint ""
		(layer "F.Cu")
		(at 124.587 -53.721 180)
		(property "Reference" "R193"
			(at -3.175 -0.29337 0)
			(unlocked yes)
			(layer "F.SilkS")
			(effects
				(font
					(size 0.7874 0.5842)
					(thickness 0.1524)
				)
			)
		)
		(property "Value" "VAL*"
			(at 0.02032 2.13233 180)
			(unlocked yes)
			(layer "F.Fab")
			(hide yes)
			(effects
				(font
					(size 0.7874 0.5842)
					(thickness 0.1524)
				)
			)
		)
		(property "Device Type" "RESISTOR-G155-14701-01,4.7KOHMA"
			(at 0.008382 1.210564 180)
			(unlocked yes)
			(layer "F.Fab")
			(hide yes)
			(effects
				(font
					(size 0.7874 0.5842)
					(thickness 0.1524)
				)
			)
		)
		(property "User Part Number" "PARTNUM*"
			(at 0.02032 4.024884 180)
			(unlocked yes)
			(layer "Cmts.User")
			(hide yes)
			(effects
				(font
					(size 0.7874 0.5842)
					(thickness 0.1524)
				)
			)
		)
		(property "Tolerance" "TOL*"
			(at 0.044704 3.05435 180)
			(unlocked yes)
			(layer "Cmts.User")
			(hide yes)
			(effects
				(font
					(size 0.7874 0.5842)
					(thickness 0.1524)
				)
			)
		)
		(duplicate_pad_numbers_are_jumpers no)
		(fp_line
			(start 1.143 0.5588)
			(end 1.143 -0.5588)
			(stroke
				(width 0.1)
				(type default)
			)
			(layer "F.SilkS")
		)
		(fp_line
			(start 1.143 -0.5588)
			(end -1.143 -0.5588)
			(stroke
				(width 0.1)
				(type default)
			)
			(layer "F.SilkS")
		)
		(fp_line
			(start -1.143 0.5588)
			(end 1.143 0.5588)
			(stroke
				(width 0.1)
				(type default)
			)
			(layer "F.SilkS")
		)
		(fp_line
			(start -1.143 -0.5588)
			(end -1.143 0.5588)
			(stroke
				(width 0.1)
				(type default)
			)
			(layer "F.SilkS")
		)
		(fp_rect
			(start -1.143 0.5588)
			(end 1.143 -0.5588)
			(stroke
				(width 0)
				(type default)
			)
			(fill no)
			(layer "F.CrtYd")
		)
		(fp_line
			(start 0.508 0.3048)
			(end 0.508 -0.3048)
			(stroke
				(width 0.1)
				(type default)
			)
			(layer "F.Fab")
		)
		(fp_line
			(start 0.508 -0.3048)
			(end -0.508 -0.3048)
			(stroke
				(width 0.1)
				(type default)
			)
			(layer "F.Fab")
		)
		(fp_line
			(start -0.508 0.3048)
			(end 0.508 0.3048)
			(stroke
				(width 0.1)
				(type default)
			)
			(layer "F.Fab")
		)
		(fp_line
			(start -0.508 -0.3048)
			(end -0.508 0.3048)
			(stroke
				(width 0.1)
				(type default)
			)
			(layer "F.Fab")
		)
		(pad "1" smd rect
			(at -0.5334 0 180)
			(size 0.7112 0.6096)
			(layers "F.Cu" "F.Mask" "F.Paste")
			(net "XP3R3V_FPGA")
		)
		(pad "2" smd rect
			(at 0.5334 0 180)
			(size 0.7112 0.6096)
			(layers "F.Cu" "F.Mask" "F.Paste")
			(net "FPGA_PROGRAM_N")
		)
		(zone
			(layer "F.Cu")
			(hatch none 0.5)
			(connect_pads
				(clearance 0)
			)
			(min_thickness 0.25)
			(keepout
				(tracks allowed)
				(vias not_allowed)
				(pads allowed)
				(copperpour not_allowed)
				(footprints allowed)
			)
			(placement
				(enabled no)
				(sheetname "")
			)
			(fill
				(thermal_gap 0.5)
				(thermal_bridge_width 0.5)
				(island_removal_mode 0)
			)
			(polygon
				(pts
					(xy 124.6632 -54.0258) (xy 124.5108 -54.0258) (xy 124.5108 -53.4162) (xy 124.6632 -53.4162)
				)
			)
		)
	)
	(footprint ""
		(layer "F.Cu")
		(at 105.6894 -59.7916)
		(property "Reference" "TP184"
			(at 3.68935 0.7874 90)
			(unlocked yes)
			(layer "F.SilkS")
			(effects
				(font
					(size 0.635 0.4064)
					(thickness 0.1524)
				)
				(justify left)
			)
		)
		(property "Value" ""
			(at 0 0 0)
			(layer "F.Fab")
			(effects
				(font
					(size 1.27 1.27)
				)
			)
		)
		(property "Device Type" "TP_PIONT-TP010CT020B030_PTH-TPA"
			(at -1.341882 0.996696 0)
			(unlocked yes)
			(layer "F.Fab")
			(hide yes)
			(effects
				(font
					(size 0.7874 0.5842)
					(thickness 0.1524)
				)
				(justify left)
			)
		)
		(duplicate_pad_numbers_are_jumpers no)
		(fp_poly
			(pts
				(arc
					(start 0.889 0)
					(mid -0.889 0)
					(end 0.889 0)
				)
			)
			(stroke
				(width 0)
				(type default)
			)
			(fill no)
			(layer "B.CrtYd")
		)
		(fp_poly
			(pts
				(arc
					(start 0.889 0)
					(mid -0.889 0)
					(end 0.889 0)
				)
			)
			(stroke
				(width 0)
				(type default)
			)
			(fill no)
			(layer "F.CrtYd")
		)
		(pad "1" thru_hole circle
			(at 0 0)
			(size 0.508 0.508)
			(drill 0.254)
			(layers "*.Cu" "*.Mask")
			(remove_unused_layers no)
			(net "IO_L22N_16")
			(clearance 0.1016)
			(padstack
				(mode front_inner_back)
				(layer "Inner"
					(shape circle)
					(size 0.508 0.508)
					(clearance 0.1016)
				)
				(layer "B.Cu"
					(shape circle)
					(size 0.762 0.762)
					(clearance -0.0254)
				)
			)
		)
	)
)
